FILE_TYPE = MULTI_PHYS_TABLE;

PART 'SCONN16_ACASPI006P06'

{========================================================================================}
:VALUE                     | PART_TYPE | MATERIAL | PART_NUMBER    = STANDARD | LIFECYCLE      | PART_NUMBER   | JEDEC_TYPE    | DESCRIPTION                               | MANUFTR | MANUF_PN          | RD_CMPLS_LVL | CMPLS_LVL | CLASS | DIP_SMD | FROM_PJ   | DATA                      | FP_ECN                | EE_CHECK_LIST | CREATOR | CREATEDAY  | PSL | STATUS | ESD_CDM | ESD_HBM | ESD_MM | MSD  | PIN_LENGTH_LONG_PIN | PIN_LENGTH_SHORT_PIN ;
{========================================================================================}
 'SCONN16_ACA-SPI-006-P06' | 'SMLF'    | 'IO'     | 'DG016000006'(!) = ''       | ''               | 'DG016000006' |'SOCKET16SXA'| 'IC SOCKET SMD 16P(SPI,SOIC)(P1.27,H5.8)' | 'LTS'   | 'ACA-SPI-006-P06' | 'EU(V1)'     | 'EP(V1)'  | 'IO'  | ''      | 'T6UB-MC' | 'LTS_ACA-SPI-006-P06.pdf' | 'ACA-SPI-006-P06.msg' | ''            | ''      | '20200811' | ''  | ''     | 'NA'    | 'NA'    | 'NA'   | 'NA' | '0 MILS'            | '0 MILS'            
 'SCONN16_ACA-SPI-006-P06' | 'SMLF'    | 'EMPTY'  | 'DG016000006'(!) = ''       | ''               | 'DG016000006' |'SOCKET16SXA'| 'IC SOCKET SMD 16P(SPI,SOIC)(P1.27,H5.8)' | 'LTS'   | 'ACA-SPI-006-P06' | 'EU(V1)'     | 'EP(V1)'  | 'IO'  | ''      | 'T6UB-MC' | 'LTS_ACA-SPI-006-P06.pdf' | 'ACA-SPI-006-P06.msg' | ''            | ''      | '20200811' | ''  | ''     | 'NA'    | 'NA'    | 'NA'   | 'NA' | '0 MILS'            | '0 MILS'            

END_PART

END.

